FILE_TYPE = MACRO_DRAWING;
SET COLOR_WIRE YELLOW;
SET COLOR_PROP ORANGE;
SET COLOR_DOT WHITE;
SET COLOR_ARC YELLOW;
SET COLOR_BODY GREEN;
SET COLOR_NOTE PURPLE;
SET PROP_DISPLAY VALUE;
SET PAGE_NUMBER P179;
FORCEADD Q_RES..2
(3475 2850);
FORCEPROP 1 LAST PART_NUMBER CS12002FB06
J 0
(3515 2725);
DISPLAY 0.978723 (3515 2725);
DISPLAY INVISIBLE (3515 2725);
FORCEPROP 1 LAST VALUE 200
J 0
(3520 2925);
DISPLAY 0.978723 (3520 2925);
FORCEPROP 1 LAST TOLERANCE 1%
J 0
(3520 2875);
DISPLAY 0.978723 (3520 2875);
FORCEPROP 1 LAST WATTAGE 1/16W
J 0
(3515 2825);
DISPLAY 0.978723 (3515 2825);
FORCEPROP 1 LAST MATERIAL CHIP
J 0
(3515 2775);
DISPLAY 0.978723 (3515 2775);
FORCEPROP 1 LAST PACK_TYPE 0402LF
J 0
(3515 2675);
DISPLAY 0.978723 (3515 2675);
FORCEPROP 1 LAST $LOCATION R497
J 0
(3520 2975);
DISPLAY 0.978723 (3520 2975);
FORCEPROP 1 LASTPIN (3475 2950) $PN 1
J 0
(3480 2912);
DISPLAY 0.787234 (3480 2912);
PAINT MONO (3480 2912);
FORCEPROP 1 LASTPIN (3475 2750) $PN 2
J 0
(3480 2760);
DISPLAY 0.787234 (3480 2760);
PAINT MONO (3480 2760);
FORCEPROP 2 LAST CDS_LIB pure_quanta
J 0
(3475 2850);
DISPLAY INVISIBLE (3475 2850);
FORCEPROP 1 LAST PATH I2
J 0
(3525 3025);
DISPLAY 0.978723 (3525 3025);
PAINT WHITE (3525 3025);
DISPLAY INVISIBLE (3525 3025);
FORCEPROP 2 LAST CDS_LOCATION R497
J 0
(3525 3075);
DISPLAY 1.021277 (3525 3075);
DISPLAY INVISIBLE (3525 3075);
FORCEPROP 0 LAST $SEC 1
J 0
(3525 3025);
DISPLAY 0.680851 (3525 3025);
PAINT MONO (3525 3025);
DISPLAY INVISIBLE (3525 3025);
FORCEPROP 2 LAST CDS_SEC 1
J 0
(3525 3075);
DISPLAY 1.021277 (3525 3075);
DISPLAY INVISIBLE (3525 3075);
FORCEADD UNIVERSAL_GND..1
(3475 2600);
FORCEPROP 3 LASTPIN (3475 2650) SIG_NAME GND\g
J 0
(3485 2660);
DISPLAY 0.659574 (3485 2660);
PAINT MONO (3485 2660);
DISPLAY INVISIBLE (3485 2660);
FORCEPROP 2 LAST CDS_LIB logical_power
J 0
(3475 2600);
PAINT MONO (3475 2600);
DISPLAY INVISIBLE (3475 2600);
FORCEPROP 1 LAST HDL_POWER GND
J 1
(3500 2525);
DISPLAY 0.872340 (3500 2525);
PAINT GREEN (3500 2525);
DISPLAY INVISIBLE (3500 2525);
FORCEPROP 1 LAST PATH I3
J 0
(3550 2600);
DISPLAY 0.872340 (3550 2600);
PAINT AQUA (3550 2600);
DISPLAY INVISIBLE (3550 2600);
FORCEPROP 2 LAST ROOM IO_SLOT
J 1
(3250 2675);
DISPLAY 0.744681 (3250 2675);
DISPLAY INVISIBLE (3250 2675);
FORCEADD EMMITSBURG_REV0P9..9
(1350 3175);
FORCEPROP 1 LAST PART_NUMBER AJ0QV2N0T00
J 0
(457 3599);
DISPLAY 0.723404 (457 3599);
PAINT GREEN (457 3599);
DISPLAY INVISIBLE (457 3599);
FORCEPROP 1 LAST MATERIAL IC
J 0
(457 3472);
DISPLAY 0.723404 (457 3472);
PAINT GREEN (457 3472);
FORCEPROP 2 LAST VALUE GFNOCPU04302300-QV2N-MM#99A1WT
J 0
(475 3800);
DISPLAY 1.021277 (475 3800);
FORCEPROP 2 LAST PART_TYPE SMLF
J 0
(475 3850);
DISPLAY 1.021277 (475 3850);
FORCEPROP 1 LAST $LOCATION U4
J 0
(457 3746);
DISPLAY 0.723404 (457 3746);
PAINT GREEN (457 3746);
FORCEPROP 2 LASTPIN (2400 3050) $PN AC13
J 0
(2410 3060);
DISPLAY 0.808511 (2410 3060);
FORCEPROP 2 LASTPIN (2400 3300) $PN A4
J 0
(2410 3310);
DISPLAY 0.808511 (2410 3310);
FORCEPROP 2 LASTPIN (2400 3100) $PN BB43
J 0
(2410 3110);
DISPLAY 0.808511 (2410 3110);
FORCEPROP 2 LASTPIN (2400 3200) $PN F1
J 0
(2410 3210);
DISPLAY 0.808511 (2410 3210);
FORCEPROP 2 LASTPIN (2400 3250) $PN H1
J 0
(2410 3260);
DISPLAY 0.808511 (2410 3260);
FORCEPROP 2 LASTPIN (300 3250) $PN L13
J 2
(290 3260);
DISPLAY 0.808511 (290 3260);
FORCEPROP 2 LASTPIN (300 3300) $PN N13
J 2
(290 3310);
DISPLAY 0.808511 (290 3310);
FORCEPROP 2 LASTPIN (2400 3150) $PN P18
J 0
(2410 3160);
DISPLAY 0.808511 (2410 3160);
FORCEPROP 1 LAST NEEDS_NO_SIZE TRUE
J 0
(1350 3175);
DISPLAY 0.723404 (1350 3175);
PAINT GREEN (1350 3175);
DISPLAY INVISIBLE (1350 3175);
FORCEPROP 1 LAST CDS_LMAN_SYM_OUTLINE -900,275,900,-275
J 0
(1350 3175);
DISPLAY 0.468085 (1350 3175);
PAINT GREEN (1350 3175);
DISPLAY INVISIBLE (1350 3175);
FORCEPROP 2 LAST CDS_LIB pure_quanta
J 0
(1350 3175);
PAINT MONO (1350 3175);
DISPLAY INVISIBLE (1350 3175);
FORCEPROP 1 LAST PATH I4
J 0
(1350 3175);
DISPLAY 0.723404 (1350 3175);
PAINT GREEN (1350 3175);
DISPLAY INVISIBLE (1350 3175);
FORCEPROP 2 LAST CDS_LOCATION U4
J 0
(450 3625);
DISPLAY 1.021277 (450 3625);
DISPLAY INVISIBLE (450 3625);
FORCEPROP 2 LAST $SEC 9
J 0
(475 3900);
DISPLAY 0.680851 (475 3900);
PAINT MONO (475 3900);
DISPLAY INVISIBLE (475 3900);
FORCEPROP 2 LAST CDS_SEC 9
J 0
(450 3625);
DISPLAY 1.021277 (450 3625);
DISPLAY INVISIBLE (450 3625);
FORCEADD QUANTA_TITLE_BLOCK_C..1
(6200 -1875);
FORCEPROP 0 LAST CDS_CON_LAST_MODIFIED Fri Aug 25 14:02:59 2023
J 0
(4315 -1860);
PAINT MONO (4315 -1860);
DISPLAY INVISIBLE (4315 -1860);
FORCEPROP 1 LAST CUSTOM_TXT_CDS <CON_LAST_MODIFIED>
J 0
(4315 -1860);
DISPLAY 0.978723 (4315 -1860);
FORCEPROP 2 LAST CUSTOM_TXT_CDS <XR_PAGE_TITLE>
J 0
(-1690 3375);
DISPLAY 0.638298 (-1690 3375);
PAINT PINK (-1690 3375);
DISPLAY INVISIBLE (-1690 3375);
FORCEPROP 2 LAST CUSTOM_TXT_CDS <Q_NUMBER>
J 0
(4797 -1772);
DISPLAY 1.212766 (4797 -1772);
FORCEPROP 1 LAST CUSTOM_TXT_CDS <NAME_2>
J 0
(3025 -1825);
FORCEPROP 1 LAST CUSTOM_TXT_CDS <NAME_1>
J 0
(3025 -1700);
FORCEPROP 1 LAST CUSTOM_TXT_CDS <Q_PROJ>
J 0
(3818 -1773);
DISPLAY 1.212766 (3818 -1773);
FORCEPROP 1 LAST CUSTOM_TXT_CDS <Q_REV>
J 0
(6016 -1772);
DISPLAY 1.212766 (6016 -1772);
FORCEPROP 1 LAST CUSTOM_TXT_CDS <CON_PAGE_NUM> OF <CON_TOTAL_PAGES>
J 0
(5754 -1857);
DISPLAY 0.978723 (5754 -1857);
FORCEPROP 1 LAST Q_TITLE EMMITSBURG - RSVD (9/10)
J 0
(-3116 -1849);
DISPLAY 1.957447 (-3116 -1849);
PAINT GREEN (-3116 -1849);
FORCEPROP 1 LAST Q_DEPT 
J 1
(2437 -1826);
DISPLAY 1.957447 (2437 -1826);
PAINT GREEN (2437 -1826);
FORCEPROP 2 LAST CDS_XR_PAGE_TITLE CR-187 : @S9S_MB_2U_LIB.S9S_MB_2U(SCH_1):PAGE187
J 0
(-1690 3375);
DISPLAY 0.638298 (-1690 3375);
PAINT PINK (-1690 3375);
DISPLAY INVISIBLE (-1690 3375);
FORCEPROP 1 LAST COMMENT_BODY TRUE
J 0
(6212 -1888);
DISPLAY 0.978723 (6212 -1888);
PAINT GREEN (6212 -1888);
DISPLAY INVISIBLE (6212 -1888);
FORCEPROP 1 LAST CDS_LMAN_SYM_OUTLINE -9475,6775,100,-125
J 0
(6200 -1875);
DISPLAY 0.468085 (6200 -1875);
PAINT GREEN (6200 -1875);
DISPLAY INVISIBLE (6200 -1875);
FORCEPROP 2 LAST CDS_LIB pure_quanta
J 0
(6200 -1875);
PAINT MONO (6200 -1875);
DISPLAY INVISIBLE (6200 -1875);
FORCEPROP 2 LAST PAGE_BORDER TRUE
J 0
(-1690 3375);
DISPLAY 0.638298 (-1690 3375);
PAINT PINK (-1690 3375);
DISPLAY INVISIBLE (-1690 3375);
WIRE 16 -1 (3475 2750)(3475 2650);
WIRE 16 -1 (3475 2950)(3475 3050);
WIRE 16 -1 (2400 3050)(3475 3050);
FORCEPROP 2 LAST SIG_NAME PD_RCOMP_1P8_3P3
J 0
(2565 3060);
DISPLAY 0.680851 (2565 3060);
PAINT WHITE (2565 3060);
WIRE 16 -1 (-775 3250)(300 3250);
FORCEPROP 0 LAST CDS_PHYS_NET_NAME FM_PCH_SLP_S4_N
J 0
(-750 3292);
PAINT MONO (-750 3292);
DISPLAY INVISIBLE (-750 3292);
FORCEPROP 0 LAST SIG_NAME TP_PCH_RSVD<13>
J 0
(-675 3260);
DISPLAY 0.680851 (-675 3260);
PAINT WHITE (-675 3260);
WIRE 16 -1 (-775 3300)(300 3300);
FORCEPROP 0 LAST CDS_PHYS_NET_NAME FM_PCH_SLP_S4_N
J 0
(-750 3342);
PAINT MONO (-750 3342);
DISPLAY INVISIBLE (-750 3342);
FORCEPROP 0 LAST SIG_NAME TP_PCH_RSVD<12>
J 0
(-675 3310);
DISPLAY 0.680851 (-675 3310);
PAINT WHITE (-675 3310);
WIRE 16 -1 (2400 3100)(3475 3100);
FORCEPROP 2 LAST SIG_NAME TP_PCH_RSVD<7>
J 0
(2565 3110);
DISPLAY 0.680851 (2565 3110);
PAINT WHITE (2565 3110);
WIRE 16 -1 (2400 3150)(3475 3150);
FORCEPROP 2 LAST SIG_NAME TP_PCH_RSVD<6>
J 0
(2565 3160);
DISPLAY 0.680851 (2565 3160);
PAINT WHITE (2565 3160);
WIRE 16 -1 (2400 3300)(3475 3300);
FORCEPROP 2 LAST SIG_NAME TP_PCH_RSVD<2>
J 0
(2565 3310);
DISPLAY 0.680851 (2565 3310);
PAINT WHITE (2565 3310);
WIRE 16 -1 (2400 3200)(3475 3200);
FORCEPROP 2 LAST SIG_NAME TP_PCH_RSVD<1>
J 0
(2565 3210);
DISPLAY 0.680851 (2565 3210);
PAINT WHITE (2565 3210);
WIRE 16 -1 (2400 3250)(3475 3250);
FORCEPROP 2 LAST SIG_NAME TP_PCH_RSVD<0>
J 0
(2565 3260);
DISPLAY 0.680851 (2565 3260);
PAINT WHITE (2565 3260);
QUIT
